# SCM (Grand Teton) — schematic netlist excerpt (pin names and nets, part order shuffled) for the footprints in the layout excerpt that follows; sources: Cadence DE-HDL packaged netlist, KiCad conversion of 12092022_DA0F0TMDCD0_F0T_Management_Board_D_brd_V3_OCP.brd

R830  Q_RES  12K 1% CHIP  pkg 0402LF  page 53 : A = U39_ADJ ; B = GND

U18  74LVC1G08GW  IC  pkg SM  page 52
  B  = PWRGD_P5V_AUX
  A  = PWRGD_P1V8_AUX_R2
  GND  = GND
  Y  = EN_P3V3_RGM
  VCC  = P3V3_LDO

(kicad_pcb
	(version 20260206)
	(generator "pcbnew")
	(generator_version "10.0")
	(general
		(thickness 1.6)
		(legacy_teardrops no)
	)
	(paper "A4")
	(title_block
		(title "12092022_DA0F0TMDCD0_F0T_Management_Board_D_brd_V3_OCP.brd")
		(comment 1 "Grand Teton / footprints 137-138 of 1440")
	)
	(layers
		(0 "F.Cu" signal "TOP")
		(4 "In1.Cu" signal "GND")
		(6 "In2.Cu" signal "IN1")
		(8 "In3.Cu" signal "GND1")
		(10 "In4.Cu" signal "IN2")
		(12 "In5.Cu" signal "VCC")
		(14 "In6.Cu" signal "VCC1")
		(16 "In7.Cu" signal "IN3")
		(18 "In8.Cu" signal "GND2")
		(20 "In9.Cu" signal "IN4")
		(22 "In10.Cu" signal "GND3")
		(2 "B.Cu" signal "BOTTOM")
		(9 "F.Adhes" user "F.Adhesive")
		(11 "B.Adhes" user "B.Adhesive")
		(13 "F.Paste" user "Package Geometry/Pastemask Top")
		(15 "B.Paste" user "Package Geometry/Pastemask Bottom")
		(5 "F.SilkS" user "Ref Des/Silkscreen Top")
		(7 "B.SilkS" user "Ref Des/Silkscreen Bottom")
		(1 "F.Mask" user "Board Geometry/Soldermask Top")
		(3 "B.Mask" user "Board Geometry/Soldermask Bottom")
		(17 "Dwgs.User" user "User.Drawings")
		(19 "Cmts.User" user "User.Comments")
		(21 "Eco1.User" user "User.Eco1")
		(23 "Eco2.User" user "User.Eco2")
		(25 "Edge.Cuts" user "Board Geometry/Outline")
		(27 "Margin" user)
		(31 "F.CrtYd" user "Package Geometry/Place Bound Top")
		(29 "B.CrtYd" user "Package Geometry/Place Bound Bottom")
		(35 "F.Fab" user "Ref Des/Assembly Top")
		(33 "B.Fab" user "Ref Des/Assembly Bottom")
	)
	(footprint ""
		(layer "F.Cu")
		(at 83.217258 -37.703506)
		(property "Reference" "R830"
			(at 0 0 0)
			(layer "F.SilkS")
			(hide yes)
			(effects
				(font
					(size 1.27 1.27)
				)
			)
		)
		(property "Value" ""
			(at 0 0 0)
			(layer "F.Fab")
			(effects
				(font
					(size 1.27 1.27)
				)
			)
		)
		(duplicate_pad_numbers_are_jumpers no)
		(fp_line
			(start -0.7874 -0.4064)
			(end 0.7874 -0.4064)
			(stroke
				(width 0.1524)
				(type default)
			)
			(layer "F.SilkS")
		)
		(fp_line
			(start -0.7874 0.4064)
			(end -0.7874 -0.4064)
			(stroke
				(width 0.1524)
				(type default)
			)
			(layer "F.SilkS")
		)
		(fp_line
			(start 0.7874 -0.4064)
			(end 0.7874 0.4064)
			(stroke
				(width 0.1524)
				(type default)
			)
			(layer "F.SilkS")
		)
		(fp_line
			(start 0.7874 0.4064)
			(end -0.7874 0.4064)
			(stroke
				(width 0.1524)
				(type default)
			)
			(layer "F.SilkS")
		)
		(fp_line
			(start -0.67945 -0.305054)
			(end -0.12065 -0.305054)
			(stroke
				(width 0.1)
				(type default)
			)
			(layer "F.Fab")
		)
		(fp_line
			(start -0.67945 0.3048)
			(end -0.67945 -0.305054)
			(stroke
				(width 0.1)
				(type default)
			)
			(layer "F.Fab")
		)
		(fp_line
			(start -0.12065 -0.305054)
			(end -0.12065 -0.2794)
			(stroke
				(width 0.1)
				(type default)
			)
			(layer "F.Fab")
		)
		(fp_line
			(start -0.12065 -0.2794)
			(end 0.12065 -0.2794)
			(stroke
				(width 0.1)
				(type default)
			)
			(layer "F.Fab")
		)
		(fp_line
			(start -0.12065 0.2794)
			(end -0.12065 0.3048)
			(stroke
				(width 0.1)
				(type default)
			)
			(layer "F.Fab")
		)
		(fp_line
			(start -0.12065 0.3048)
			(end -0.67945 0.3048)
			(stroke
				(width 0.1)
				(type default)
			)
			(layer "F.Fab")
		)
		(fp_line
			(start 0.120396 0.2794)
			(end -0.12065 0.2794)
			(stroke
				(width 0.1)
				(type default)
			)
			(layer "F.Fab")
		)
		(fp_line
			(start 0.120396 0.3048)
			(end 0.120396 0.2794)
			(stroke
				(width 0.1)
				(type default)
			)
			(layer "F.Fab")
		)
		(fp_line
			(start 0.12065 -0.3048)
			(end 0.67945 -0.3048)
			(stroke
				(width 0.1)
				(type default)
			)
			(layer "F.Fab")
		)
		(fp_line
			(start 0.12065 -0.2794)
			(end 0.12065 -0.3048)
			(stroke
				(width 0.1)
				(type default)
			)
			(layer "F.Fab")
		)
		(fp_line
			(start 0.67945 -0.3048)
			(end 0.67945 0.3048)
			(stroke
				(width 0.1)
				(type default)
			)
			(layer "F.Fab")
		)
		(fp_line
			(start 0.67945 0.3048)
			(end 0.120396 0.3048)
			(stroke
				(width 0.1)
				(type default)
			)
			(layer "F.Fab")
		)
		(pad "1" smd circle
			(at -0.40005 0)
			(size 0 0)
			(layers "F.Cu" "F.Mask" "F.Paste")
			(net "U39_ADJ")
		)
		(pad "2" smd circle
			(at 0.40005 0)
			(size 0 0)
			(layers "F.Cu" "F.Mask" "F.Paste")
			(net "GND")
		)
	)
	(footprint ""
		(layer "F.Cu")
		(at 15.1638 -51.1048 -90)
		(property "Reference" "U18"
			(at 0.8636 -1.83007 90)
			(unlocked yes)
			(layer "F.SilkS")
			(effects
				(font
					(size 0.7874 0.5842)
					(thickness 0.1524)
				)
			)
		)
		(property "Value" ""
			(at 0 0 270)
			(layer "F.Fab")
			(effects
				(font
					(size 1.27 1.27)
				)
			)
		)
		(duplicate_pad_numbers_are_jumpers no)
		(fp_line
			(start -1.7018 1.1176)
			(end -1.7018 -1.1176)
			(stroke
				(width 0.1524)
				(type default)
			)
			(layer "F.SilkS")
		)
		(fp_line
			(start 1.7018 1.1176)
			(end -1.7018 1.1176)
			(stroke
				(width 0.1524)
				(type default)
			)
			(layer "F.SilkS")
		)
		(fp_line
			(start 0 -0.7112)
			(end -0.254 -1.1176)
			(stroke
				(width 0.1524)
				(type default)
			)
			(layer "F.SilkS")
		)
		(fp_line
			(start -0.254 -1.1176)
			(end -1.7018 -1.1176)
			(stroke
				(width 0.1524)
				(type default)
			)
			(layer "F.SilkS")
		)
		(fp_line
			(start 0.254 -1.1176)
			(end 0 -0.7112)
			(stroke
				(width 0.1524)
				(type default)
			)
			(layer "F.SilkS")
		)
		(fp_line
			(start 1.7018 -1.1176)
			(end 1.7018 1.1176)
			(stroke
				(width 0.1524)
				(type default)
			)
			(layer "F.SilkS")
		)
		(fp_line
			(start 1.7018 -1.1176)
			(end 0.254 -1.1176)
			(stroke
				(width 0.1524)
				(type default)
			)
			(layer "F.SilkS")
		)
		(fp_poly
			(pts
				(xy -1.559814 -1.3589) (xy -1.788414 -1.9431) (xy -1.356614 -1.9431)
			)
			(stroke
				(width 0)
				(type default)
			)
			(fill yes)
			(layer "F.SilkS")
		)
		(fp_line
			(start -1.5494 1.1176)
			(end -1.5494 -1.1176)
			(stroke
				(width 0.1)
				(type default)
			)
			(layer "F.Fab")
		)
		(fp_line
			(start 1.5494 1.1176)
			(end -1.5494 1.1176)
			(stroke
				(width 0.1)
				(type default)
			)
			(layer "F.Fab")
		)
		(fp_line
			(start -0.254 -1.1176)
			(end -1.5494 -1.1176)
			(stroke
				(width 0.1)
				(type default)
			)
			(layer "F.Fab")
		)
		(fp_line
			(start 0.254 -1.1176)
			(end -0.254 -1.1176)
			(stroke
				(width 0.1)
				(type default)
			)
			(layer "F.Fab")
		)
		(fp_line
			(start 1.5494 -1.1176)
			(end 1.5494 1.1176)
			(stroke
				(width 0.1)
				(type default)
			)
			(layer "F.Fab")
		)
		(fp_line
			(start 1.5494 -1.1176)
			(end 0.254 -1.1176)
			(stroke
				(width 0.1)
				(type default)
			)
			(layer "F.Fab")
		)
		(fp_poly
			(pts
				(xy -1.8161 -0.675386) (xy -2.4003 -0.446786) (xy -2.4003 -0.878586)
			)
			(stroke
				(width 0)
				(type default)
			)
			(fill yes)
			(layer "F.Fab")
		)
		(pad "1" smd rect
			(at -0.962406 -0.649986 180)
			(size 0.3302 1.1684)
			(layers "F.Cu" "F.Mask" "F.Paste")
			(net "PWRGD_P5V_AUX")
		)
		(pad "2" smd rect
			(at -0.962406 0 180)
			(size 0.3302 1.1684)
			(layers "F.Cu" "F.Mask" "F.Paste")
			(net "PWRGD_P1V8_AUX_R2")
		)
		(pad "3" smd rect
			(at -0.962406 0.649986 180)
			(size 0.3302 1.1684)
			(layers "F.Cu" "F.Mask" "F.Paste")
			(net "GND")
		)
		(pad "4" smd rect
			(at 0.962406 0.649986 180)
			(size 0.3302 1.1684)
			(layers "F.Cu" "F.Mask" "F.Paste")
			(net "EN_P3V3_RGM")
		)
		(pad "5" smd rect
			(at 0.962406 -0.649986 180)
			(size 0.3302 1.1684)
			(layers "F.Cu" "F.Mask" "F.Paste")
			(net "P3V3_LDO")
		)
	)
)
